(kicad_pcb
	(version 20260206)
	(generator "pcbnew")
	(generator_version "10.0")
	(general
		(thickness 1.6)
		(legacy_teardrops no)
	)
	(paper "A4")
	(title_block
		(title "03242023_DA0F0TMBIJ0_F0T_Motherboard_J_brd_V01_OCP.brd")
		(comment 1 "Grand Teton / footprints 5652-5658 of 6105")
	)
	(layers
		(0 "F.Cu" signal "TOP")
		(4 "In1.Cu" signal "GND")
		(6 "In2.Cu" signal "IN1")
		(8 "In3.Cu" signal "GND1")
		(10 "In4.Cu" signal "IN2")
		(12 "In5.Cu" signal "GND2")
		(14 "In6.Cu" signal "IN3")
		(16 "In7.Cu" signal "GND3")
		(18 "In8.Cu" signal "VCC")
		(20 "In9.Cu" signal "VCC1")
		(22 "In10.Cu" signal "GND4")
		(24 "In11.Cu" signal "IN4")
		(26 "In12.Cu" signal "GND5")
		(28 "In13.Cu" signal "IN5")
		(30 "In14.Cu" signal "GND6")
		(32 "In15.Cu" signal "IN6")
		(34 "In16.Cu" signal "GND7")
		(2 "B.Cu" signal "BOTTOM")
		(9 "F.Adhes" user "F.Adhesive")
		(11 "B.Adhes" user "B.Adhesive")
		(13 "F.Paste" user "Package Geometry/Pastemask Top")
		(15 "B.Paste" user "Package Geometry/Pastemask Bottom")
		(5 "F.SilkS" user "Ref Des/Silkscreen Top")
		(7 "B.SilkS" user "Ref Des/Silkscreen Bottom")
		(1 "F.Mask" user "Board Geometry/Soldermask Top")
		(3 "B.Mask" user "Board Geometry/Soldermask Bottom")
		(17 "Dwgs.User" user "User.Drawings")
		(19 "Cmts.User" user "User.Comments")
		(21 "Eco1.User" user "User.Eco1")
		(23 "Eco2.User" user "User.Eco2")
		(25 "Edge.Cuts" user "Board Geometry/Outline")
		(27 "Margin" user)
		(31 "F.CrtYd" user "Package Geometry/Place Bound Top")
		(29 "B.CrtYd" user "Package Geometry/Place Bound Bottom")
		(35 "F.Fab" user "Ref Des/Assembly Top")
		(33 "B.Fab" user "Ref Des/Assembly Bottom")
	)
	(footprint ""
		(layer "B.Cu")
		(at 450.70649 -3.871468 -90)
		(property "Reference" "R1505"
			(at 0 0 90)
			(layer "B.SilkS")
			(hide yes)
			(effects
				(font
					(size 1.27 1.27)
				)
				(justify mirror)
			)
		)
		(property "Value" ""
			(at 0 0 90)
			(layer "B.Fab")
			(effects
				(font
					(size 1.27 1.27)
				)
				(justify mirror)
			)
		)
		(duplicate_pad_numbers_are_jumpers no)
		(fp_line
			(start -0.7874 0.4064)
			(end 0.7874 0.4064)
			(stroke
				(width 0.1524)
				(type default)
			)
			(layer "B.SilkS")
		)
		(fp_line
			(start 0.7874 0.4064)
			(end 0.7874 -0.4064)
			(stroke
				(width 0.1524)
				(type default)
			)
			(layer "B.SilkS")
		)
		(fp_line
			(start -0.7874 -0.4064)
			(end -0.7874 0.4064)
			(stroke
				(width 0.1524)
				(type default)
			)
			(layer "B.SilkS")
		)
		(fp_line
			(start 0.7874 -0.4064)
			(end -0.7874 -0.4064)
			(stroke
				(width 0.1524)
				(type default)
			)
			(layer "B.SilkS")
		)
		(fp_line
			(start -0.67945 0.3048)
			(end -0.120396 0.3048)
			(stroke
				(width 0.1)
				(type default)
			)
			(layer "B.Fab")
		)
		(fp_line
			(start -0.120396 0.3048)
			(end -0.120396 0.2794)
			(stroke
				(width 0.1)
				(type default)
			)
			(layer "B.Fab")
		)
		(fp_line
			(start 0.12065 0.3048)
			(end 0.67945 0.3048)
			(stroke
				(width 0.1)
				(type default)
			)
			(layer "B.Fab")
		)
		(fp_line
			(start 0.67945 0.3048)
			(end 0.67945 -0.305054)
			(stroke
				(width 0.1)
				(type default)
			)
			(layer "B.Fab")
		)
		(fp_line
			(start -0.120396 0.2794)
			(end 0.12065 0.2794)
			(stroke
				(width 0.1)
				(type default)
			)
			(layer "B.Fab")
		)
		(fp_line
			(start 0.12065 0.2794)
			(end 0.12065 0.3048)
			(stroke
				(width 0.1)
				(type default)
			)
			(layer "B.Fab")
		)
		(fp_line
			(start -0.12065 -0.2794)
			(end -0.12065 -0.3048)
			(stroke
				(width 0.1)
				(type default)
			)
			(layer "B.Fab")
		)
		(fp_line
			(start 0.12065 -0.2794)
			(end -0.12065 -0.2794)
			(stroke
				(width 0.1)
				(type default)
			)
			(layer "B.Fab")
		)
		(fp_line
			(start -0.67945 -0.3048)
			(end -0.67945 0.3048)
			(stroke
				(width 0.1)
				(type default)
			)
			(layer "B.Fab")
		)
		(fp_line
			(start -0.12065 -0.3048)
			(end -0.67945 -0.3048)
			(stroke
				(width 0.1)
				(type default)
			)
			(layer "B.Fab")
		)
		(fp_line
			(start 0.12065 -0.305054)
			(end 0.12065 -0.2794)
			(stroke
				(width 0.1)
				(type default)
			)
			(layer "B.Fab")
		)
		(fp_line
			(start 0.67945 -0.305054)
			(end 0.12065 -0.305054)
			(stroke
				(width 0.1)
				(type default)
			)
			(layer "B.Fab")
		)
		(pad "1" smd circle
			(at 0.40005 0 90)
			(size 0 0)
			(layers "B.Cu" "B.Mask" "B.Paste")
			(net "RST_OCP_V3_1_BUF_N")
		)
		(pad "2" smd circle
			(at -0.40005 0 90)
			(size 0 0)
			(layers "B.Cu" "B.Mask" "B.Paste")
			(net "RST_PERST3_OCP_SFF_N")
		)
	)
	(footprint ""
		(layer "B.Cu")
		(at 352.730308 -237.709202 -90)
		(property "Reference" "C1406"
			(at 0 0 90)
			(layer "B.SilkS")
			(hide yes)
			(effects
				(font
					(size 1.27 1.27)
				)
				(justify mirror)
			)
		)
		(property "Value" ""
			(at 0 0 90)
			(layer "B.Fab")
			(effects
				(font
					(size 1.27 1.27)
				)
				(justify mirror)
			)
		)
		(duplicate_pad_numbers_are_jumpers no)
		(fp_line
			(start -1.2954 0.5842)
			(end 1.2954 0.5842)
			(stroke
				(width 0.1524)
				(type default)
			)
			(layer "B.SilkS")
		)
		(fp_line
			(start 1.2954 0.5842)
			(end 1.2954 -0.5842)
			(stroke
				(width 0.1524)
				(type default)
			)
			(layer "B.SilkS")
		)
		(fp_line
			(start -1.2954 -0.5842)
			(end -1.2954 0.5842)
			(stroke
				(width 0.1524)
				(type default)
			)
			(layer "B.SilkS")
		)
		(fp_line
			(start 0 -0.5842)
			(end 0 0.5842)
			(stroke
				(width 0.1524)
				(type default)
			)
			(layer "B.SilkS")
		)
		(fp_line
			(start 1.2954 -0.5842)
			(end -1.2954 -0.5842)
			(stroke
				(width 0.1524)
				(type default)
			)
			(layer "B.SilkS")
		)
		(fp_line
			(start -0.8636 0.4572)
			(end 0.8636 0.4572)
			(stroke
				(width 0.1)
				(type default)
			)
			(layer "B.Fab")
		)
		(fp_line
			(start 0.8636 0.4572)
			(end 0.8636 0.4064)
			(stroke
				(width 0.1)
				(type default)
			)
			(layer "B.Fab")
		)
		(fp_line
			(start -1.1938 0.4064)
			(end -0.8636 0.4064)
			(stroke
				(width 0.1)
				(type default)
			)
			(layer "B.Fab")
		)
		(fp_line
			(start -0.8636 0.4064)
			(end -0.8636 0.4572)
			(stroke
				(width 0.1)
				(type default)
			)
			(layer "B.Fab")
		)
		(fp_line
			(start 0.8636 0.4064)
			(end 1.1938 0.4064)
			(stroke
				(width 0.1)
				(type default)
			)
			(layer "B.Fab")
		)
		(fp_line
			(start 1.1938 0.4064)
			(end 1.1938 -0.4064)
			(stroke
				(width 0.1)
				(type default)
			)
			(layer "B.Fab")
		)
		(fp_line
			(start -1.1938 -0.4064)
			(end -1.1938 0.4064)
			(stroke
				(width 0.1)
				(type default)
			)
			(layer "B.Fab")
		)
		(fp_line
			(start -0.8636 -0.4064)
			(end -1.1938 -0.4064)
			(stroke
				(width 0.1)
				(type default)
			)
			(layer "B.Fab")
		)
		(fp_line
			(start 0.8636 -0.4064)
			(end 0.8636 -0.4572)
			(stroke
				(width 0.1)
				(type default)
			)
			(layer "B.Fab")
		)
		(fp_line
			(start 1.1938 -0.4064)
			(end 0.8636 -0.4064)
			(stroke
				(width 0.1)
				(type default)
			)
			(layer "B.Fab")
		)
		(fp_line
			(start -0.8636 -0.4572)
			(end -0.8636 -0.4064)
			(stroke
				(width 0.1)
				(type default)
			)
			(layer "B.Fab")
		)
		(fp_line
			(start 0.8636 -0.4572)
			(end -0.8636 -0.4572)
			(stroke
				(width 0.1)
				(type default)
			)
			(layer "B.Fab")
		)
		(pad "1" smd rect
			(at 0.7366 0 180)
			(size 0.7112 0.8128)
			(layers "B.Cu" "B.Mask" "B.Paste")
			(net "PVNN_MAIN_CPU0")
		)
		(pad "2" smd rect
			(at -0.7366 0 180)
			(size 0.7112 0.8128)
			(layers "B.Cu" "B.Mask" "B.Paste")
			(net "GND")
		)
	)
	(footprint ""
		(layer "B.Cu")
		(at 158.82366 -15.563088 180)
		(property "Reference" "R601"
			(at 0 0 0)
			(layer "B.SilkS")
			(hide yes)
			(effects
				(font
					(size 1.27 1.27)
				)
				(justify mirror)
			)
		)
		(property "Value" ""
			(at 0 0 0)
			(layer "B.Fab")
			(effects
				(font
					(size 1.27 1.27)
				)
				(justify mirror)
			)
		)
		(duplicate_pad_numbers_are_jumpers no)
		(fp_line
			(start 0.7874 0.4064)
			(end 0.7874 -0.4064)
			(stroke
				(width 0.1524)
				(type default)
			)
			(layer "B.SilkS")
		)
		(fp_line
			(start 0.7874 -0.4064)
			(end -0.7874 -0.4064)
			(stroke
				(width 0.1524)
				(type default)
			)
			(layer "B.SilkS")
		)
		(fp_line
			(start -0.7874 0.4064)
			(end 0.7874 0.4064)
			(stroke
				(width 0.1524)
				(type default)
			)
			(layer "B.SilkS")
		)
		(fp_line
			(start -0.7874 -0.4064)
			(end -0.7874 0.4064)
			(stroke
				(width 0.1524)
				(type default)
			)
			(layer "B.SilkS")
		)
		(fp_line
			(start 0.67945 0.3048)
			(end 0.67945 -0.305054)
			(stroke
				(width 0.1)
				(type default)
			)
			(layer "B.Fab")
		)
		(fp_line
			(start 0.67945 -0.305054)
			(end 0.12065 -0.305054)
			(stroke
				(width 0.1)
				(type default)
			)
			(layer "B.Fab")
		)
		(fp_line
			(start 0.12065 0.3048)
			(end 0.67945 0.3048)
			(stroke
				(width 0.1)
				(type default)
			)
			(layer "B.Fab")
		)
		(fp_line
			(start 0.12065 0.2794)
			(end 0.12065 0.3048)
			(stroke
				(width 0.1)
				(type default)
			)
			(layer "B.Fab")
		)
		(fp_line
			(start 0.12065 -0.2794)
			(end -0.12065 -0.2794)
			(stroke
				(width 0.1)
				(type default)
			)
			(layer "B.Fab")
		)
		(fp_line
			(start 0.12065 -0.305054)
			(end 0.12065 -0.2794)
			(stroke
				(width 0.1)
				(type default)
			)
			(layer "B.Fab")
		)
		(fp_line
			(start -0.120396 0.3048)
			(end -0.120396 0.2794)
			(stroke
				(width 0.1)
				(type default)
			)
			(layer "B.Fab")
		)
		(fp_line
			(start -0.120396 0.2794)
			(end 0.12065 0.2794)
			(stroke
				(width 0.1)
				(type default)
			)
			(layer "B.Fab")
		)
		(fp_line
			(start -0.12065 -0.2794)
			(end -0.12065 -0.3048)
			(stroke
				(width 0.1)
				(type default)
			)
			(layer "B.Fab")
		)
		(fp_line
			(start -0.12065 -0.3048)
			(end -0.67945 -0.3048)
			(stroke
				(width 0.1)
				(type default)
			)
			(layer "B.Fab")
		)
		(fp_line
			(start -0.67945 0.3048)
			(end -0.120396 0.3048)
			(stroke
				(width 0.1)
				(type default)
			)
			(layer "B.Fab")
		)
		(fp_line
			(start -0.67945 -0.3048)
			(end -0.67945 0.3048)
			(stroke
				(width 0.1)
				(type default)
			)
			(layer "B.Fab")
		)
		(pad "1" smd circle
			(at 0.40005 0)
			(size 0 0)
			(layers "B.Cu" "B.Mask" "B.Paste")
			(net "SMB_FAN_3V3AUX_SDA")
		)
		(pad "2" smd circle
			(at -0.40005 0)
			(size 0 0)
			(layers "B.Cu" "B.Mask" "B.Paste")
			(net "P3V3_AUX")
		)
	)
	(footprint ""
		(layer "B.Cu")
		(at 118.158768 -210.194144)
		(property "Reference" "C486"
			(at 0 0 0)
			(layer "B.SilkS")
			(hide yes)
			(effects
				(font
					(size 1.27 1.27)
				)
				(justify mirror)
			)
		)
		(property "Value" ""
			(at 0 0 0)
			(layer "B.Fab")
			(effects
				(font
					(size 1.27 1.27)
				)
				(justify mirror)
			)
		)
		(duplicate_pad_numbers_are_jumpers no)
		(fp_line
			(start -1.524 -0.762)
			(end -1.524 0.762)
			(stroke
				(width 0.1524)
				(type default)
			)
			(layer "B.SilkS")
		)
		(fp_line
			(start -1.524 0.762)
			(end 1.524 0.762)
			(stroke
				(width 0.1524)
				(type default)
			)
			(layer "B.SilkS")
		)
		(fp_line
			(start 1.524 -0.762)
			(end -1.524 -0.762)
			(stroke
				(width 0.1524)
				(type default)
			)
			(layer "B.SilkS")
		)
		(fp_line
			(start 1.524 0.762)
			(end 1.524 -0.762)
			(stroke
				(width 0.1524)
				(type default)
			)
			(layer "B.SilkS")
		)
		(fp_line
			(start -1.1049 -0.724916)
			(end 1.1049 -0.724916)
			(stroke
				(width 0.1)
				(type default)
			)
			(layer "B.Fab")
		)
		(fp_line
			(start -1.1049 0.724916)
			(end -1.1049 -0.724916)
			(stroke
				(width 0.1)
				(type default)
			)
			(layer "B.Fab")
		)
		(fp_line
			(start 1.1049 -0.724916)
			(end 1.1049 0.724916)
			(stroke
				(width 0.1)
				(type default)
			)
			(layer "B.Fab")
		)
		(fp_line
			(start 1.1049 0.724916)
			(end -1.1049 0.724916)
			(stroke
				(width 0.1)
				(type default)
			)
			(layer "B.Fab")
		)
		(pad "1" smd rect
			(at 0.889 0)
			(size 1.016 1.27)
			(layers "B.Cu" "B.Mask" "B.Paste")
			(net "PVCCINFAON_CPU1")
		)
		(pad "2" smd rect
			(at -0.889 0)
			(size 1.016 1.27)
			(layers "B.Cu" "B.Mask" "B.Paste")
			(net "GND")
		)
	)
	(footprint ""
		(layer "B.Cu")
		(at 245.818406 -98.092006 180)
		(property "Reference" "R912"
			(at 0 0 0)
			(layer "B.SilkS")
			(hide yes)
			(effects
				(font
					(size 1.27 1.27)
				)
				(justify mirror)
			)
		)
		(property "Value" ""
			(at 0 0 0)
			(layer "B.Fab")
			(effects
				(font
					(size 1.27 1.27)
				)
				(justify mirror)
			)
		)
		(duplicate_pad_numbers_are_jumpers no)
		(fp_line
			(start 0.7874 0.4064)
			(end 0.7874 -0.4064)
			(stroke
				(width 0.1524)
				(type default)
			)
			(layer "B.SilkS")
		)
		(fp_line
			(start 0.7874 -0.4064)
			(end -0.7874 -0.4064)
			(stroke
				(width 0.1524)
				(type default)
			)
			(layer "B.SilkS")
		)
		(fp_line
			(start -0.7874 0.4064)
			(end 0.7874 0.4064)
			(stroke
				(width 0.1524)
				(type default)
			)
			(layer "B.SilkS")
		)
		(fp_line
			(start -0.7874 -0.4064)
			(end -0.7874 0.4064)
			(stroke
				(width 0.1524)
				(type default)
			)
			(layer "B.SilkS")
		)
		(fp_line
			(start 0.67945 0.3048)
			(end 0.67945 -0.305054)
			(stroke
				(width 0.1)
				(type default)
			)
			(layer "B.Fab")
		)
		(fp_line
			(start 0.67945 -0.305054)
			(end 0.12065 -0.305054)
			(stroke
				(width 0.1)
				(type default)
			)
			(layer "B.Fab")
		)
		(fp_line
			(start 0.12065 0.3048)
			(end 0.67945 0.3048)
			(stroke
				(width 0.1)
				(type default)
			)
			(layer "B.Fab")
		)
		(fp_line
			(start 0.12065 0.2794)
			(end 0.12065 0.3048)
			(stroke
				(width 0.1)
				(type default)
			)
			(layer "B.Fab")
		)
		(fp_line
			(start 0.12065 -0.2794)
			(end -0.12065 -0.2794)
			(stroke
				(width 0.1)
				(type default)
			)
			(layer "B.Fab")
		)
		(fp_line
			(start 0.12065 -0.305054)
			(end 0.12065 -0.2794)
			(stroke
				(width 0.1)
				(type default)
			)
			(layer "B.Fab")
		)
		(fp_line
			(start -0.120396 0.3048)
			(end -0.120396 0.2794)
			(stroke
				(width 0.1)
				(type default)
			)
			(layer "B.Fab")
		)
		(fp_line
			(start -0.120396 0.2794)
			(end 0.12065 0.2794)
			(stroke
				(width 0.1)
				(type default)
			)
			(layer "B.Fab")
		)
		(fp_line
			(start -0.12065 -0.2794)
			(end -0.12065 -0.3048)
			(stroke
				(width 0.1)
				(type default)
			)
			(layer "B.Fab")
		)
		(fp_line
			(start -0.12065 -0.3048)
			(end -0.67945 -0.3048)
			(stroke
				(width 0.1)
				(type default)
			)
			(layer "B.Fab")
		)
		(fp_line
			(start -0.67945 0.3048)
			(end -0.120396 0.3048)
			(stroke
				(width 0.1)
				(type default)
			)
			(layer "B.Fab")
		)
		(fp_line
			(start -0.67945 -0.3048)
			(end -0.67945 0.3048)
			(stroke
				(width 0.1)
				(type default)
			)
			(layer "B.Fab")
		)
		(pad "1" smd circle
			(at 0.40005 0)
			(size 0 0)
			(layers "B.Cu" "B.Mask" "B.Paste")
			(net "P3V3_AUX")
		)
		(pad "2" smd circle
			(at -0.40005 0)
			(size 0 0)
			(layers "B.Cu" "B.Mask" "B.Paste")
			(net "CLK_CK440_SMB_ADDR0")
		)
	)
	(footprint ""
		(layer "B.Cu")
		(at 36.968938 -128.4097)
		(property "Reference" "R2569"
			(at 0 0 0)
			(layer "B.SilkS")
			(hide yes)
			(effects
				(font
					(size 1.27 1.27)
				)
				(justify mirror)
			)
		)
		(property "Value" ""
			(at 0 0 0)
			(layer "B.Fab")
			(effects
				(font
					(size 1.27 1.27)
				)
				(justify mirror)
			)
		)
		(duplicate_pad_numbers_are_jumpers no)
		(fp_line
			(start -0.7874 -0.4064)
			(end -0.7874 0.4064)
			(stroke
				(width 0.1524)
				(type default)
			)
			(layer "B.SilkS")
		)
		(fp_line
			(start -0.7874 0.4064)
			(end 0.7874 0.4064)
			(stroke
				(width 0.1524)
				(type default)
			)
			(layer "B.SilkS")
		)
		(fp_line
			(start 0.7874 -0.4064)
			(end -0.7874 -0.4064)
			(stroke
				(width 0.1524)
				(type default)
			)
			(layer "B.SilkS")
		)
		(fp_line
			(start 0.7874 0.4064)
			(end 0.7874 -0.4064)
			(stroke
				(width 0.1524)
				(type default)
			)
			(layer "B.SilkS")
		)
		(fp_line
			(start -0.67945 -0.3048)
			(end -0.67945 0.3048)
			(stroke
				(width 0.1)
				(type default)
			)
			(layer "B.Fab")
		)
		(fp_line
			(start -0.67945 0.3048)
			(end -0.120396 0.3048)
			(stroke
				(width 0.1)
				(type default)
			)
			(layer "B.Fab")
		)
		(fp_line
			(start -0.12065 -0.3048)
			(end -0.67945 -0.3048)
			(stroke
				(width 0.1)
				(type default)
			)
			(layer "B.Fab")
		)
		(fp_line
			(start -0.12065 -0.2794)
			(end -0.12065 -0.3048)
			(stroke
				(width 0.1)
				(type default)
			)
			(layer "B.Fab")
		)
		(fp_line
			(start -0.120396 0.2794)
			(end 0.12065 0.2794)
			(stroke
				(width 0.1)
				(type default)
			)
			(layer "B.Fab")
		)
		(fp_line
			(start -0.120396 0.3048)
			(end -0.120396 0.2794)
			(stroke
				(width 0.1)
				(type default)
			)
			(layer "B.Fab")
		)
		(fp_line
			(start 0.12065 -0.305054)
			(end 0.12065 -0.2794)
			(stroke
				(width 0.1)
				(type default)
			)
			(layer "B.Fab")
		)
		(fp_line
			(start 0.12065 -0.2794)
			(end -0.12065 -0.2794)
			(stroke
				(width 0.1)
				(type default)
			)
			(layer "B.Fab")
		)
		(fp_line
			(start 0.12065 0.2794)
			(end 0.12065 0.3048)
			(stroke
				(width 0.1)
				(type default)
			)
			(layer "B.Fab")
		)
		(fp_line
			(start 0.12065 0.3048)
			(end 0.67945 0.3048)
			(stroke
				(width 0.1)
				(type default)
			)
			(layer "B.Fab")
		)
		(fp_line
			(start 0.67945 -0.305054)
			(end 0.12065 -0.305054)
			(stroke
				(width 0.1)
				(type default)
			)
			(layer "B.Fab")
		)
		(fp_line
			(start 0.67945 0.3048)
			(end 0.67945 -0.305054)
			(stroke
				(width 0.1)
				(type default)
			)
			(layer "B.Fab")
		)
		(pad "1" smd circle
			(at 0.40005 0 180)
			(size 0 0)
			(layers "B.Cu" "B.Mask" "B.Paste")
			(net "P3V3_AUX")
		)
		(pad "2" smd circle
			(at -0.40005 0 180)
			(size 0 0)
			(layers "B.Cu" "B.Mask" "B.Paste")
			(net "PVCCINFAON_CPU1_PIN_ALERT")
		)
	)
	(footprint ""
		(layer "B.Cu")
		(at 380.808738 -337.161124 90)
		(property "Reference" "PC261_P0_5"
			(at 0 0 90)
			(layer "B.SilkS")
			(hide yes)
			(effects
				(font
					(size 1.27 1.27)
				)
				(justify mirror)
			)
		)
		(property "Value" ""
			(at 0 0 90)
			(layer "B.Fab")
			(effects
				(font
					(size 1.27 1.27)
				)
				(justify mirror)
			)
		)
		(duplicate_pad_numbers_are_jumpers no)
		(fp_line
			(start 1.524 -0.762)
			(end -1.524 -0.762)
			(stroke
				(width 0.1524)
				(type default)
			)
			(layer "B.SilkS")
		)
		(fp_line
			(start -1.524 -0.762)
			(end -1.524 0.762)
			(stroke
				(width 0.1524)
				(type default)
			)
			(layer "B.SilkS")
		)
		(fp_line
			(start 1.524 0.762)
			(end 1.524 -0.762)
			(stroke
				(width 0.1524)
				(type default)
			)
			(layer "B.SilkS")
		)
		(fp_line
			(start -1.524 0.762)
			(end 1.524 0.762)
			(stroke
				(width 0.1524)
				(type default)
			)
			(layer "B.SilkS")
		)
		(fp_line
			(start 1.1049 -0.724916)
			(end 1.1049 0.724916)
			(stroke
				(width 0.1)
				(type default)
			)
			(layer "B.Fab")
		)
		(fp_line
			(start -1.1049 -0.724916)
			(end 1.1049 -0.724916)
			(stroke
				(width 0.1)
				(type default)
			)
			(layer "B.Fab")
		)
		(fp_line
			(start 1.1049 0.724916)
			(end -1.1049 0.724916)
			(stroke
				(width 0.1)
				(type default)
			)
			(layer "B.Fab")
		)
		(fp_line
			(start -1.1049 0.724916)
			(end -1.1049 -0.724916)
			(stroke
				(width 0.1)
				(type default)
			)
			(layer "B.Fab")
		)
		(pad "1" smd rect
			(at 0.889 0 90)
			(size 1.016 1.27)
			(layers "B.Cu" "B.Mask" "B.Paste")
			(net "SW_P12V_PVCCIN_CPU0_FLT")
		)
		(pad "2" smd rect
			(at -0.889 0 90)
			(size 1.016 1.27)
			(layers "B.Cu" "B.Mask" "B.Paste")
			(net "GND")
		)
	)
)
